# S9S_MB_2U (Grand Teton) — schematic netlist excerpt (pin names and nets, part order shuffled) for the footprints in the layout excerpt that follows; sources: Cadence DE-HDL packaged netlist, KiCad conversion of 03242023_DA0F0TMBIJ0_F0T_Motherboard_J_brd_V01_OCP.brd

C364  Q_CAP  47UF 4V 20% X6S  pkg C0805  page 75 : A = PVCCIN_CPU0 ; B = GND
R1290  Q_RES  22 1% EMPTY  pkg 0402LF  page 154 : A = OCP_SFF_RBT_ARB_IN_R ; B = OCP_SFF_RBT_ARB_IN

(kicad_pcb
	(version 20260206)
	(generator "pcbnew")
	(generator_version "10.0")
	(general
		(thickness 1.6)
		(legacy_teardrops no)
	)
	(paper "A4")
	(title_block
		(title "03242023_DA0F0TMBIJ0_F0T_Motherboard_J_brd_V01_OCP.brd")
		(comment 1 "Grand Teton / footprints 4739-4740 of 6105")
	)
	(layers
		(0 "F.Cu" signal "TOP")
		(4 "In1.Cu" signal "GND")
		(6 "In2.Cu" signal "IN1")
		(8 "In3.Cu" signal "GND1")
		(10 "In4.Cu" signal "IN2")
		(12 "In5.Cu" signal "GND2")
		(14 "In6.Cu" signal "IN3")
		(16 "In7.Cu" signal "GND3")
		(18 "In8.Cu" signal "VCC")
		(20 "In9.Cu" signal "VCC1")
		(22 "In10.Cu" signal "GND4")
		(24 "In11.Cu" signal "IN4")
		(26 "In12.Cu" signal "GND5")
		(28 "In13.Cu" signal "IN5")
		(30 "In14.Cu" signal "GND6")
		(32 "In15.Cu" signal "IN6")
		(34 "In16.Cu" signal "GND7")
		(2 "B.Cu" signal "BOTTOM")
		(9 "F.Adhes" user "F.Adhesive")
		(11 "B.Adhes" user "B.Adhesive")
		(13 "F.Paste" user "Package Geometry/Pastemask Top")
		(15 "B.Paste" user "Package Geometry/Pastemask Bottom")
		(5 "F.SilkS" user "Ref Des/Silkscreen Top")
		(7 "B.SilkS" user "Ref Des/Silkscreen Bottom")
		(1 "F.Mask" user "Board Geometry/Soldermask Top")
		(3 "B.Mask" user "Board Geometry/Soldermask Bottom")
		(17 "Dwgs.User" user "User.Drawings")
		(19 "Cmts.User" user "User.Comments")
		(21 "Eco1.User" user "User.Eco1")
		(23 "Eco2.User" user "User.Eco2")
		(25 "Edge.Cuts" user "Board Geometry/Outline")
		(27 "Margin" user)
		(31 "F.CrtYd" user "Package Geometry/Place Bound Top")
		(29 "B.CrtYd" user "Package Geometry/Place Bound Bottom")
		(35 "F.Fab" user "Ref Des/Assembly Top")
		(33 "B.Fab" user "Ref Des/Assembly Bottom")
	)
	(footprint ""
		(layer "B.Cu")
		(at 191.47409 -79.05623 -90)
		(property "Reference" "R1290"
			(at 0 0 90)
			(layer "B.SilkS")
			(hide yes)
			(effects
				(font
					(size 1.27 1.27)
				)
				(justify mirror)
			)
		)
		(property "Value" ""
			(at 0 0 90)
			(layer "B.Fab")
			(effects
				(font
					(size 1.27 1.27)
				)
				(justify mirror)
			)
		)
		(duplicate_pad_numbers_are_jumpers no)
		(fp_line
			(start -0.7874 0.4064)
			(end 0.7874 0.4064)
			(stroke
				(width 0.1524)
				(type default)
			)
			(layer "B.SilkS")
		)
		(fp_line
			(start 0.7874 0.4064)
			(end 0.7874 -0.4064)
			(stroke
				(width 0.1524)
				(type default)
			)
			(layer "B.SilkS")
		)
		(fp_line
			(start -0.7874 -0.4064)
			(end -0.7874 0.4064)
			(stroke
				(width 0.1524)
				(type default)
			)
			(layer "B.SilkS")
		)
		(fp_line
			(start 0.7874 -0.4064)
			(end -0.7874 -0.4064)
			(stroke
				(width 0.1524)
				(type default)
			)
			(layer "B.SilkS")
		)
		(fp_line
			(start -0.67945 0.3048)
			(end -0.120396 0.3048)
			(stroke
				(width 0.1)
				(type default)
			)
			(layer "B.Fab")
		)
		(fp_line
			(start -0.120396 0.3048)
			(end -0.120396 0.2794)
			(stroke
				(width 0.1)
				(type default)
			)
			(layer "B.Fab")
		)
		(fp_line
			(start 0.12065 0.3048)
			(end 0.67945 0.3048)
			(stroke
				(width 0.1)
				(type default)
			)
			(layer "B.Fab")
		)
		(fp_line
			(start 0.67945 0.3048)
			(end 0.67945 -0.305054)
			(stroke
				(width 0.1)
				(type default)
			)
			(layer "B.Fab")
		)
		(fp_line
			(start -0.120396 0.2794)
			(end 0.12065 0.2794)
			(stroke
				(width 0.1)
				(type default)
			)
			(layer "B.Fab")
		)
		(fp_line
			(start 0.12065 0.2794)
			(end 0.12065 0.3048)
			(stroke
				(width 0.1)
				(type default)
			)
			(layer "B.Fab")
		)
		(fp_line
			(start -0.12065 -0.2794)
			(end -0.12065 -0.3048)
			(stroke
				(width 0.1)
				(type default)
			)
			(layer "B.Fab")
		)
		(fp_line
			(start 0.12065 -0.2794)
			(end -0.12065 -0.2794)
			(stroke
				(width 0.1)
				(type default)
			)
			(layer "B.Fab")
		)
		(fp_line
			(start -0.67945 -0.3048)
			(end -0.67945 0.3048)
			(stroke
				(width 0.1)
				(type default)
			)
			(layer "B.Fab")
		)
		(fp_line
			(start -0.12065 -0.3048)
			(end -0.67945 -0.3048)
			(stroke
				(width 0.1)
				(type default)
			)
			(layer "B.Fab")
		)
		(fp_line
			(start 0.12065 -0.305054)
			(end 0.12065 -0.2794)
			(stroke
				(width 0.1)
				(type default)
			)
			(layer "B.Fab")
		)
		(fp_line
			(start 0.67945 -0.305054)
			(end 0.12065 -0.305054)
			(stroke
				(width 0.1)
				(type default)
			)
			(layer "B.Fab")
		)
		(pad "1" smd rect
			(at 0.40005 0 270)
			(size 0.4572 0.508)
			(layers "B.Cu" "B.Mask" "B.Paste")
			(net "OCP_SFF_RBT_ARB_IN_R")
		)
		(pad "2" smd rect
			(at -0.40005 0 270)
			(size 0.4572 0.508)
			(layers "B.Cu" "B.Mask" "B.Paste")
			(net "OCP_SFF_RBT_ARB_IN")
		)
	)
	(footprint ""
		(layer "B.Cu")
		(at 364.342934 -252.176026 -90)
		(property "Reference" "C364"
			(at 0 0 90)
			(layer "B.SilkS")
			(hide yes)
			(effects
				(font
					(size 1.27 1.27)
				)
				(justify mirror)
			)
		)
		(property "Value" ""
			(at 0 0 90)
			(layer "B.Fab")
			(effects
				(font
					(size 1.27 1.27)
				)
				(justify mirror)
			)
		)
		(duplicate_pad_numbers_are_jumpers no)
		(fp_line
			(start -1.524 0.762)
			(end 1.524 0.762)
			(stroke
				(width 0.1524)
				(type default)
			)
			(layer "B.SilkS")
		)
		(fp_line
			(start 1.524 0.762)
			(end 1.524 -0.762)
			(stroke
				(width 0.1524)
				(type default)
			)
			(layer "B.SilkS")
		)
		(fp_line
			(start -1.524 -0.762)
			(end -1.524 0.762)
			(stroke
				(width 0.1524)
				(type default)
			)
			(layer "B.SilkS")
		)
		(fp_line
			(start 1.524 -0.762)
			(end -1.524 -0.762)
			(stroke
				(width 0.1524)
				(type default)
			)
			(layer "B.SilkS")
		)
		(fp_line
			(start -1.1049 0.724916)
			(end -1.1049 -0.724916)
			(stroke
				(width 0.1)
				(type default)
			)
			(layer "B.Fab")
		)
		(fp_line
			(start 1.1049 0.724916)
			(end -1.1049 0.724916)
			(stroke
				(width 0.1)
				(type default)
			)
			(layer "B.Fab")
		)
		(fp_line
			(start -1.1049 -0.724916)
			(end 1.1049 -0.724916)
			(stroke
				(width 0.1)
				(type default)
			)
			(layer "B.Fab")
		)
		(fp_line
			(start 1.1049 -0.724916)
			(end 1.1049 0.724916)
			(stroke
				(width 0.1)
				(type default)
			)
			(layer "B.Fab")
		)
		(pad "1" smd rect
			(at 0.889 0 270)
			(size 1.016 1.27)
			(layers "B.Cu" "B.Mask" "B.Paste")
			(net "PVCCIN_CPU0")
		)
		(pad "2" smd rect
			(at -0.889 0 270)
			(size 1.016 1.27)
			(layers "B.Cu" "B.Mask" "B.Paste")
			(net "GND")
		)
	)
)
